(kicad_pcb
	(version 20260206)
	(generator "pcbnew")
	(generator_version "10.0")
	(general
		(thickness 1.6)
		(legacy_teardrops no)
	)
	(paper "A4")
	(title_block
		(title "01162023_DA0F0TEBIF0_F0T_Expander_BD_F_brd_V02_OCP.brd")
		(comment 1 "Grand Teton / footprints 6365-6370 of 9728")
	)
	(layers
		(0 "F.Cu" signal "TOP")
		(4 "In1.Cu" signal "GND")
		(6 "In2.Cu" signal "VCC")
		(8 "In3.Cu" signal "VCC1")
		(10 "In4.Cu" signal "GND1")
		(12 "In5.Cu" signal "IN1")
		(14 "In6.Cu" signal "GND2")
		(16 "In7.Cu" signal "IN2")
		(18 "In8.Cu" signal "GND3")
		(20 "In9.Cu" signal "IN3")
		(22 "In10.Cu" signal "GND4")
		(24 "In11.Cu" signal "IN4")
		(26 "In12.Cu" signal "GND5")
		(28 "In13.Cu" signal "IN5")
		(30 "In14.Cu" signal "GND6")
		(32 "In15.Cu" signal "IN6")
		(34 "In16.Cu" signal "GND7")
		(2 "B.Cu" signal "BOTTOM")
		(9 "F.Adhes" user "F.Adhesive")
		(11 "B.Adhes" user "B.Adhesive")
		(13 "F.Paste" user "Package Geometry/Pastemask Top")
		(15 "B.Paste" user "Package Geometry/Pastemask Bottom")
		(5 "F.SilkS" user "Ref Des/Silkscreen Top")
		(7 "B.SilkS" user "Ref Des/Silkscreen Bottom")
		(1 "F.Mask" user "Board Geometry/Soldermask Top")
		(3 "B.Mask" user "Board Geometry/Soldermask Bottom")
		(17 "Dwgs.User" user "User.Drawings")
		(19 "Cmts.User" user "User.Comments")
		(21 "Eco1.User" user "User.Eco1")
		(23 "Eco2.User" user "User.Eco2")
		(25 "Edge.Cuts" user "Board Geometry/Outline")
		(27 "Margin" user)
		(31 "F.CrtYd" user "Package Geometry/Place Bound Top")
		(29 "B.CrtYd" user "Package Geometry/Place Bound Bottom")
		(35 "F.Fab" user "Ref Des/Assembly Top")
		(33 "B.Fab" user "Ref Des/Assembly Bottom")
	)
	(footprint ""
		(layer "F.Cu")
		(at 148.511514 -296.445432 -90)
		(property "Reference" "R4568"
			(at 0 0 270)
			(layer "F.SilkS")
			(hide yes)
			(effects
				(font
					(size 1.27 1.27)
				)
			)
		)
		(property "Value" ""
			(at 0 0 270)
			(layer "F.Fab")
			(effects
				(font
					(size 1.27 1.27)
				)
			)
		)
		(duplicate_pad_numbers_are_jumpers no)
		(fp_line
			(start -0.7874 0.4064)
			(end -0.7874 -0.4064)
			(stroke
				(width 0.1524)
				(type default)
			)
			(layer "F.SilkS")
		)
		(fp_line
			(start 0.7874 0.4064)
			(end -0.7874 0.4064)
			(stroke
				(width 0.1524)
				(type default)
			)
			(layer "F.SilkS")
		)
		(fp_line
			(start -0.7874 -0.4064)
			(end 0.7874 -0.4064)
			(stroke
				(width 0.1524)
				(type default)
			)
			(layer "F.SilkS")
		)
		(fp_line
			(start 0.7874 -0.4064)
			(end 0.7874 0.4064)
			(stroke
				(width 0.1524)
				(type default)
			)
			(layer "F.SilkS")
		)
		(fp_line
			(start -0.67945 0.3048)
			(end -0.67945 -0.305054)
			(stroke
				(width 0.1)
				(type default)
			)
			(layer "F.Fab")
		)
		(fp_line
			(start -0.12065 0.3048)
			(end -0.67945 0.3048)
			(stroke
				(width 0.1)
				(type default)
			)
			(layer "F.Fab")
		)
		(fp_line
			(start 0.120396 0.3048)
			(end 0.120396 0.2794)
			(stroke
				(width 0.1)
				(type default)
			)
			(layer "F.Fab")
		)
		(fp_line
			(start 0.67945 0.3048)
			(end 0.120396 0.3048)
			(stroke
				(width 0.1)
				(type default)
			)
			(layer "F.Fab")
		)
		(fp_line
			(start -0.12065 0.2794)
			(end -0.12065 0.3048)
			(stroke
				(width 0.1)
				(type default)
			)
			(layer "F.Fab")
		)
		(fp_line
			(start 0.120396 0.2794)
			(end -0.12065 0.2794)
			(stroke
				(width 0.1)
				(type default)
			)
			(layer "F.Fab")
		)
		(fp_line
			(start -0.12065 -0.2794)
			(end 0.12065 -0.2794)
			(stroke
				(width 0.1)
				(type default)
			)
			(layer "F.Fab")
		)
		(fp_line
			(start 0.12065 -0.2794)
			(end 0.12065 -0.3048)
			(stroke
				(width 0.1)
				(type default)
			)
			(layer "F.Fab")
		)
		(fp_line
			(start 0.12065 -0.3048)
			(end 0.67945 -0.3048)
			(stroke
				(width 0.1)
				(type default)
			)
			(layer "F.Fab")
		)
		(fp_line
			(start 0.67945 -0.3048)
			(end 0.67945 0.3048)
			(stroke
				(width 0.1)
				(type default)
			)
			(layer "F.Fab")
		)
		(fp_line
			(start -0.67945 -0.305054)
			(end -0.12065 -0.305054)
			(stroke
				(width 0.1)
				(type default)
			)
			(layer "F.Fab")
		)
		(fp_line
			(start -0.12065 -0.305054)
			(end -0.12065 -0.2794)
			(stroke
				(width 0.1)
				(type default)
			)
			(layer "F.Fab")
		)
		(pad "1" smd circle
			(at -0.40005 0 270)
			(size 0 0)
			(layers "F.Cu" "F.Mask" "F.Paste")
			(net "PCEPLL0_VDDA18_PEX1")
		)
		(pad "2" smd circle
			(at 0.40005 0 270)
			(size 0 0)
			(layers "F.Cu" "F.Mask" "F.Paste")
			(net "PCEPLL0_VDDA18_PEX1_R")
		)
	)
	(footprint ""
		(layer "F.Cu")
		(at 419.771576 -25.342342 -90)
		(property "Reference" "R451"
			(at 0 0 270)
			(layer "F.SilkS")
			(hide yes)
			(effects
				(font
					(size 1.27 1.27)
				)
			)
		)
		(property "Value" ""
			(at 0 0 270)
			(layer "F.Fab")
			(effects
				(font
					(size 1.27 1.27)
				)
			)
		)
		(duplicate_pad_numbers_are_jumpers no)
		(fp_line
			(start -0.7874 0.4064)
			(end -0.7874 -0.4064)
			(stroke
				(width 0.1524)
				(type default)
			)
			(layer "F.SilkS")
		)
		(fp_line
			(start 0.7874 0.4064)
			(end -0.7874 0.4064)
			(stroke
				(width 0.1524)
				(type default)
			)
			(layer "F.SilkS")
		)
		(fp_line
			(start -0.7874 -0.4064)
			(end 0.7874 -0.4064)
			(stroke
				(width 0.1524)
				(type default)
			)
			(layer "F.SilkS")
		)
		(fp_line
			(start 0.7874 -0.4064)
			(end 0.7874 0.4064)
			(stroke
				(width 0.1524)
				(type default)
			)
			(layer "F.SilkS")
		)
		(fp_line
			(start -0.67945 0.3048)
			(end -0.67945 -0.305054)
			(stroke
				(width 0.1)
				(type default)
			)
			(layer "F.Fab")
		)
		(fp_line
			(start -0.12065 0.3048)
			(end -0.67945 0.3048)
			(stroke
				(width 0.1)
				(type default)
			)
			(layer "F.Fab")
		)
		(fp_line
			(start 0.120396 0.3048)
			(end 0.120396 0.2794)
			(stroke
				(width 0.1)
				(type default)
			)
			(layer "F.Fab")
		)
		(fp_line
			(start 0.67945 0.3048)
			(end 0.120396 0.3048)
			(stroke
				(width 0.1)
				(type default)
			)
			(layer "F.Fab")
		)
		(fp_line
			(start -0.12065 0.2794)
			(end -0.12065 0.3048)
			(stroke
				(width 0.1)
				(type default)
			)
			(layer "F.Fab")
		)
		(fp_line
			(start 0.120396 0.2794)
			(end -0.12065 0.2794)
			(stroke
				(width 0.1)
				(type default)
			)
			(layer "F.Fab")
		)
		(fp_line
			(start -0.12065 -0.2794)
			(end 0.12065 -0.2794)
			(stroke
				(width 0.1)
				(type default)
			)
			(layer "F.Fab")
		)
		(fp_line
			(start 0.12065 -0.2794)
			(end 0.12065 -0.3048)
			(stroke
				(width 0.1)
				(type default)
			)
			(layer "F.Fab")
		)
		(fp_line
			(start 0.12065 -0.3048)
			(end 0.67945 -0.3048)
			(stroke
				(width 0.1)
				(type default)
			)
			(layer "F.Fab")
		)
		(fp_line
			(start 0.67945 -0.3048)
			(end 0.67945 0.3048)
			(stroke
				(width 0.1)
				(type default)
			)
			(layer "F.Fab")
		)
		(fp_line
			(start -0.67945 -0.305054)
			(end -0.12065 -0.305054)
			(stroke
				(width 0.1)
				(type default)
			)
			(layer "F.Fab")
		)
		(fp_line
			(start -0.12065 -0.305054)
			(end -0.12065 -0.2794)
			(stroke
				(width 0.1)
				(type default)
			)
			(layer "F.Fab")
		)
		(pad "1" smd circle
			(at -0.40005 0 270)
			(size 0 0)
			(layers "F.Cu" "F.Mask" "F.Paste")
			(net "P3V3_SSD14")
		)
		(pad "2" smd circle
			(at 0.40005 0 270)
			(size 0 0)
			(layers "F.Cu" "F.Mask" "F.Paste")
			(net "DUALPORT_N_SSD14")
		)
	)
	(footprint ""
		(layer "F.Cu")
		(at 194.932808 -410.296868 -90)
		(property "Reference" "R500"
			(at 0 0 270)
			(layer "F.SilkS")
			(hide yes)
			(effects
				(font
					(size 1.27 1.27)
				)
			)
		)
		(property "Value" ""
			(at 0 0 270)
			(layer "F.Fab")
			(effects
				(font
					(size 1.27 1.27)
				)
			)
		)
		(duplicate_pad_numbers_are_jumpers no)
		(fp_line
			(start -0.7874 0.4064)
			(end -0.7874 -0.4064)
			(stroke
				(width 0.1524)
				(type default)
			)
			(layer "F.SilkS")
		)
		(fp_line
			(start 0.7874 0.4064)
			(end -0.7874 0.4064)
			(stroke
				(width 0.1524)
				(type default)
			)
			(layer "F.SilkS")
		)
		(fp_line
			(start -0.7874 -0.4064)
			(end 0.7874 -0.4064)
			(stroke
				(width 0.1524)
				(type default)
			)
			(layer "F.SilkS")
		)
		(fp_line
			(start 0.7874 -0.4064)
			(end 0.7874 0.4064)
			(stroke
				(width 0.1524)
				(type default)
			)
			(layer "F.SilkS")
		)
		(fp_line
			(start -0.67945 0.3048)
			(end -0.67945 -0.305054)
			(stroke
				(width 0.1)
				(type default)
			)
			(layer "F.Fab")
		)
		(fp_line
			(start -0.12065 0.3048)
			(end -0.67945 0.3048)
			(stroke
				(width 0.1)
				(type default)
			)
			(layer "F.Fab")
		)
		(fp_line
			(start 0.120396 0.3048)
			(end 0.120396 0.2794)
			(stroke
				(width 0.1)
				(type default)
			)
			(layer "F.Fab")
		)
		(fp_line
			(start 0.67945 0.3048)
			(end 0.120396 0.3048)
			(stroke
				(width 0.1)
				(type default)
			)
			(layer "F.Fab")
		)
		(fp_line
			(start -0.12065 0.2794)
			(end -0.12065 0.3048)
			(stroke
				(width 0.1)
				(type default)
			)
			(layer "F.Fab")
		)
		(fp_line
			(start 0.120396 0.2794)
			(end -0.12065 0.2794)
			(stroke
				(width 0.1)
				(type default)
			)
			(layer "F.Fab")
		)
		(fp_line
			(start -0.12065 -0.2794)
			(end 0.12065 -0.2794)
			(stroke
				(width 0.1)
				(type default)
			)
			(layer "F.Fab")
		)
		(fp_line
			(start 0.12065 -0.2794)
			(end 0.12065 -0.3048)
			(stroke
				(width 0.1)
				(type default)
			)
			(layer "F.Fab")
		)
		(fp_line
			(start 0.12065 -0.3048)
			(end 0.67945 -0.3048)
			(stroke
				(width 0.1)
				(type default)
			)
			(layer "F.Fab")
		)
		(fp_line
			(start 0.67945 -0.3048)
			(end 0.67945 0.3048)
			(stroke
				(width 0.1)
				(type default)
			)
			(layer "F.Fab")
		)
		(fp_line
			(start -0.67945 -0.305054)
			(end -0.12065 -0.305054)
			(stroke
				(width 0.1)
				(type default)
			)
			(layer "F.Fab")
		)
		(fp_line
			(start -0.12065 -0.305054)
			(end -0.12065 -0.2794)
			(stroke
				(width 0.1)
				(type default)
			)
			(layer "F.Fab")
		)
		(pad "1" smd circle
			(at -0.40005 0 270)
			(size 0 0)
			(layers "F.Cu" "F.Mask" "F.Paste")
			(net "SMB_ALERT_HSC_R_N")
		)
		(pad "2" smd circle
			(at 0.40005 0 270)
			(size 0 0)
			(layers "F.Cu" "F.Mask" "F.Paste")
			(net "SMB_ALERT_HSC_N")
		)
	)
	(footprint ""
		(layer "F.Cu")
		(at 196.119242 -134.394702 180)
		(property "Reference" "C230"
			(at 0 0 180)
			(layer "F.SilkS")
			(hide yes)
			(effects
				(font
					(size 1.27 1.27)
				)
			)
		)
		(property "Value" ""
			(at 0 0 180)
			(layer "F.Fab")
			(effects
				(font
					(size 1.27 1.27)
				)
			)
		)
		(duplicate_pad_numbers_are_jumpers no)
		(fp_line
			(start 0.299974 0.150114)
			(end -0.299974 0.150114)
			(stroke
				(width 0.1)
				(type default)
			)
			(layer "F.Fab")
		)
		(fp_line
			(start 0.299974 -0.150114)
			(end 0.299974 0.150114)
			(stroke
				(width 0.1)
				(type default)
			)
			(layer "F.Fab")
		)
		(fp_line
			(start -0.299974 0.150114)
			(end -0.299974 -0.150114)
			(stroke
				(width 0.1)
				(type default)
			)
			(layer "F.Fab")
		)
		(fp_line
			(start -0.299974 -0.150114)
			(end 0.299974 -0.150114)
			(stroke
				(width 0.1)
				(type default)
			)
			(layer "F.Fab")
		)
		(pad "1" smd rect
			(at -0.2667 0 180)
			(size 0.3048 0.381)
			(layers "F.Cu" "F.Mask" "F.Paste")
			(net "P5E_PEX1_STN0_TX_DP<6>")
		)
		(pad "2" smd rect
			(at 0.2667 0 180)
			(size 0.3048 0.381)
			(layers "F.Cu" "F.Mask" "F.Paste")
			(net "P5E_PEX1_STN0_TX_C_DP<6>")
		)
	)
	(footprint ""
		(layer "F.Cu")
		(at 190.920624 -70.307454 90)
		(property "Reference" "PC838"
			(at 0 0 90)
			(layer "F.SilkS")
			(hide yes)
			(effects
				(font
					(size 1.27 1.27)
				)
			)
		)
		(property "Value" ""
			(at 0 0 90)
			(layer "F.Fab")
			(effects
				(font
					(size 1.27 1.27)
				)
			)
		)
		(duplicate_pad_numbers_are_jumpers no)
		(fp_line
			(start 0.7874 -0.4064)
			(end 0.7874 0.4064)
			(stroke
				(width 0.1524)
				(type default)
			)
			(layer "F.SilkS")
		)
		(fp_line
			(start -0.7874 -0.4064)
			(end 0.7874 -0.4064)
			(stroke
				(width 0.1524)
				(type default)
			)
			(layer "F.SilkS")
		)
		(fp_line
			(start 0.7874 0.4064)
			(end -0.7874 0.4064)
			(stroke
				(width 0.1524)
				(type default)
			)
			(layer "F.SilkS")
		)
		(fp_line
			(start -0.7874 0.4064)
			(end -0.7874 -0.4064)
			(stroke
				(width 0.1524)
				(type default)
			)
			(layer "F.SilkS")
		)
		(fp_line
			(start -0.12065 -0.305054)
			(end -0.12065 -0.2794)
			(stroke
				(width 0.1)
				(type default)
			)
			(layer "F.Fab")
		)
		(fp_line
			(start -0.67945 -0.305054)
			(end -0.12065 -0.305054)
			(stroke
				(width 0.1)
				(type default)
			)
			(layer "F.Fab")
		)
		(fp_line
			(start 0.67945 -0.3048)
			(end 0.67945 0.3048)
			(stroke
				(width 0.1)
				(type default)
			)
			(layer "F.Fab")
		)
		(fp_line
			(start 0.12065 -0.3048)
			(end 0.67945 -0.3048)
			(stroke
				(width 0.1)
				(type default)
			)
			(layer "F.Fab")
		)
		(fp_line
			(start 0.12065 -0.2794)
			(end 0.12065 -0.3048)
			(stroke
				(width 0.1)
				(type default)
			)
			(layer "F.Fab")
		)
		(fp_line
			(start -0.12065 -0.2794)
			(end 0.12065 -0.2794)
			(stroke
				(width 0.1)
				(type default)
			)
			(layer "F.Fab")
		)
		(fp_line
			(start 0.120396 0.2794)
			(end -0.12065 0.2794)
			(stroke
				(width 0.1)
				(type default)
			)
			(layer "F.Fab")
		)
		(fp_line
			(start -0.12065 0.2794)
			(end -0.12065 0.3048)
			(stroke
				(width 0.1)
				(type default)
			)
			(layer "F.Fab")
		)
		(fp_line
			(start 0.67945 0.3048)
			(end 0.120396 0.3048)
			(stroke
				(width 0.1)
				(type default)
			)
			(layer "F.Fab")
		)
		(fp_line
			(start 0.120396 0.3048)
			(end 0.120396 0.2794)
			(stroke
				(width 0.1)
				(type default)
			)
			(layer "F.Fab")
		)
		(fp_line
			(start -0.12065 0.3048)
			(end -0.67945 0.3048)
			(stroke
				(width 0.1)
				(type default)
			)
			(layer "F.Fab")
		)
		(fp_line
			(start -0.67945 0.3048)
			(end -0.67945 -0.305054)
			(stroke
				(width 0.1)
				(type default)
			)
			(layer "F.Fab")
		)
		(pad "1" smd circle
			(at -0.40005 0 90)
			(size 0 0)
			(layers "F.Cu" "F.Mask" "F.Paste")
			(net "P12V_AUX")
		)
		(pad "2" smd circle
			(at 0.40005 0 90)
			(size 0 0)
			(layers "F.Cu" "F.Mask" "F.Paste")
			(net "GND")
		)
	)
	(footprint ""
		(layer "F.Cu")
		(at 284.810454 -18.61439 90)
		(property "Reference" "U135"
			(at -1.24079 2.312416 90)
			(unlocked yes)
			(layer "F.SilkS")
			(effects
				(font
					(size 0.7874 0.5842)
					(thickness 0.1524)
				)
				(justify left)
			)
		)
		(property "Value" ""
			(at 0 0 90)
			(layer "F.Fab")
			(effects
				(font
					(size 1.27 1.27)
				)
			)
		)
		(duplicate_pad_numbers_are_jumpers no)
		(fp_line
			(start 1.463548 -1.549908)
			(end 1.463548 1.549908)
			(stroke
				(width 0.1524)
				(type default)
			)
			(layer "F.SilkS")
		)
		(fp_line
			(start 0.762 -1.549908)
			(end 1.463548 -1.549908)
			(stroke
				(width 0.1524)
				(type default)
			)
			(layer "F.SilkS")
		)
		(fp_line
			(start -0.787908 -1.549908)
			(end 0 -0.762)
			(stroke
				(width 0.1524)
				(type default)
			)
			(layer "F.SilkS")
		)
		(fp_line
			(start -1.463548 -1.549908)
			(end -0.787908 -1.549908)
			(stroke
				(width 0.1524)
				(type default)
			)
			(layer "F.SilkS")
		)
		(fp_line
			(start 0 -0.762)
			(end 0.762 -1.549908)
			(stroke
				(width 0.1524)
				(type default)
			)
			(layer "F.SilkS")
		)
		(fp_line
			(start 1.463548 1.549908)
			(end -1.463548 1.549908)
			(stroke
				(width 0.1524)
				(type default)
			)
			(layer "F.SilkS")
		)
		(fp_line
			(start -1.463548 1.549908)
			(end -1.463548 -1.549908)
			(stroke
				(width 0.1524)
				(type default)
			)
			(layer "F.SilkS")
		)
		(fp_poly
			(pts
				(xy -3.46202 -1.44907) (xy -2.84226 -1.13919) (xy -3.46202 -0.82931)
			)
			(stroke
				(width 0)
				(type default)
			)
			(fill yes)
			(layer "F.SilkS")
		)
		(fp_line
			(start 1.549908 -1.549908)
			(end 1.549908 1.549908)
			(stroke
				(width 0.1)
				(type default)
			)
			(layer "F.Fab")
		)
		(fp_line
			(start -1.549908 -1.549908)
			(end 1.549908 -1.549908)
			(stroke
				(width 0.1)
				(type default)
			)
			(layer "F.Fab")
		)
		(fp_line
			(start 1.549908 1.549908)
			(end -1.549908 1.549908)
			(stroke
				(width 0.1)
				(type default)
			)
			(layer "F.Fab")
		)
		(fp_line
			(start -1.549908 1.549908)
			(end -1.549908 -1.549908)
			(stroke
				(width 0.1)
				(type default)
			)
			(layer "F.Fab")
		)
		(fp_poly
			(pts
				(xy -3.4798 -1.359916) (xy -2.86004 -1.050036) (xy -3.4798 -0.740156)
			)
			(stroke
				(width 0)
				(type default)
			)
			(fill yes)
			(layer "F.Fab")
		)
		(pad "1" smd rect
			(at -2.175002 -1.050036 180)
			(size 0.6096 1.1684)
			(layers "F.Cu" "F.Mask" "F.Paste")
			(net "P3V3_SSD9")
		)
		(pad "2" smd rect
			(at -2.175002 -0.32512 180)
			(size 0.4318 1.1684)
			(layers "F.Cu" "F.Mask" "F.Paste")
			(net "SMB_ISO_SSD9_SCL")
		)
		(pad "3" smd rect
			(at -2.175002 0.32512 180)
			(size 0.4318 1.1684)
			(layers "F.Cu" "F.Mask" "F.Paste")
			(net "SMB_ISO_SSD9_SDA")
		)
		(pad "4" smd rect
			(at -2.175002 1.050036 180)
			(size 0.6096 1.1684)
			(layers "F.Cu" "F.Mask" "F.Paste")
			(net "GND")
		)
		(pad "5" smd rect
			(at 2.175002 1.050036 180)
			(size 0.6096 1.1684)
			(layers "F.Cu" "F.Mask" "F.Paste")
			(net "SMB_SSD9_ISO_EN")
		)
		(pad "6" smd rect
			(at 2.175002 0.32512 180)
			(size 0.4318 1.1684)
			(layers "F.Cu" "F.Mask" "F.Paste")
			(net "SMB_BIC_I2C9_MUX1_SSD9_R_SDA")
		)
		(pad "7" smd rect
			(at 2.175002 -0.32512 180)
			(size 0.4318 1.1684)
			(layers "F.Cu" "F.Mask" "F.Paste")
			(net "SMB_BIC_I2C9_MUX1_SSD9_R_SCL")
		)
		(pad "8" smd rect
			(at 2.175002 -1.050036 180)
			(size 0.6096 1.1684)
			(layers "F.Cu" "F.Mask" "F.Paste")
			(net "P3V3_AUX")
		)
	)
)
